# Stackup_F0T_PDB_Converter_10L_2p36mm_IT-170GT_RTF_Rev0p2_20211201.xls — Vendor Stackup (pcb-stackup)
| STACKUP |  |  |  | Target Z (ohms) - MicroStrip |  |  |  |  |  |  |  | 50 |  |  | Breakout |
|  |  |  |  | Target Z (ohms) - StripLine |  |  |  |  |  |  |  | 50 |  |  |  |
|  |  |  |  | Z tolerance |  |  |  |  |  |  |  | 0.1 |  |  |  |
|  |  |  |  | Z Type |  |  |  |  |  |  |  | Single |  |  | Single |
| Layer# | Material | Description |  | Copper Weight (oz) | Thickness (mil) | Tolerance (mil) | Glass Fabric | Er | Vendor Thickness (mil) | Vendor Glass Fabric | Vendor Er | Width | Vendor Width | Vendor Impedance | Width |
|  |  |  | Soldermask |  | 0.6 |  |  | 3.8 |  |  |  |  |  |  |  |
| 1 |  |  | TOP | 0.5+plating | 1.95 |  |  |  |  |  |  | 6.8 |  |  | 4 |
|  | IT-170GT |  | PP |  | 4 | ±0.709 | 106x2 | 3.87 |  |  |  |  |  |  |  |
| 2 |  |  | GND | 2 (RTF) | 2.6 |  |  |  |  |  |  |  |  |  |  |
|  | IT-170GT |  | CORE |  | 6 | ±0.984 | 1080x2 | 3.89 |  |  |  |  |  |  |  |
| 3 |  |  | IN1 | 1 (RTF) | 1.3 |  |  |  |  |  |  | 5.1 |  |  | 4 |
|  | IT-170GT |  | PP |  | 6 | ±0.984 | 3313x1+1078x1 | 3.89 |  |  |  |  |  |  |  |
| 4 |  |  | GND1 | 2 (RTF) | 2.6 |  |  |  |  |  |  |  |  |  |  |
|  | IT-170GT |  | CORE |  | 6 | ±0.984 | 1080x2 | 3.89 |  |  |  |  |  |  |  |
| 5 |  |  | VCC | 2 (RTF) | 2.6 |  |  |  |  |  |  |  |  |  |  |
|  | IT-170GT |  | PP |  | 25.6 | ±2.52 | Vendor Define | 4.08 |  |  |  |  |  |  |  |
| 6 |  |  | VCC1 | 2 (RTF) | 2.6 |  |  |  |  |  |  |  |  |  |  |
|  | IT-170GT |  | CORE |  | 6 | ±0.984 | 1080x2 | 3.89 |  |  |  |  |  |  |  |
| 7 |  |  | GND2 | 2 (RTF) | 2.6 |  |  |  |  |  |  |  |  |  |  |
|  | IT-170GT |  | PP |  | 6 | ±0.984 | 3313x1+1078x1 | 3.89 |  |  |  |  |  |  |  |
| 8 |  |  | IN2 | 1 (RTF) | 1.3 |  |  |  |  |  |  | 5.1 |  |  | 4 |
|  | IT-170GT |  | CORE |  | 6 | ±0.984 | 1080x2 | 3.89 |  |  |  |  |  |  |  |
| 9 |  |  | GND3 | 2 (RTF) | 2.6 |  |  |  |  |  |  |  |  |  |  |
|  | IT-170GT |  | PP |  | 4 | ±0.709 | 106x2 | 3.87 |  |  |  |  |  |  |  |
| 10 |  |  | BOTTOM | 0.5+plating | 1.95 |  |  |  |  |  |  | 6.8 |  |  | 4 |
|  |  |  | Soldermask |  | 0.6 |  |  | 3.8 |  |  |  |  |  |  |  |
|  |  |  |  | Total | 92.89999999999998 | ±10% |  |  | 0 |  |  |  |  |  |  |
